# T6G (Grand Teton) — schematic netlist excerpt (pin names and nets, part order shuffled) for the footprints in the layout excerpt that follows; sources: Cadence DE-HDL packaged netlist, KiCad conversion of 04192023_DAF0TMB3IC0_F0TG_MB_C_brd_V02_OCP.brd

J107  CONN112_10137002101LF  CONN112_10137002-101LF IO  pkg HSD_F112D8_P2W1-2_RDH  page 117
  A1  = NC_J107_A1
  A2  = GND
  A3  = NC_J107_A3
  A4  = GND
  A5  = NC_J107_A5
  A6  = GND
  A7  = SWB_HSC_PWRGD
  A8  = GND
  B1  = GND
  B2  = P5E_CPU0_P0_RX_BUF_DN<9>
  B3  = GND
  B4  = P5E_CPU0_P0_RX_BUF_DN<11>
  B5  = GND
  B6  = P5E_CPU0_P0_RX_BUF_DN<13>
  B7  = GND
  B8  = P5E_CPU0_P0_RX_BUF_DN<15>
  C1  = P5E_CPU0_P0_RX_BUF_DN<8>
  C2  = P5E_CPU0_P0_RX_BUF_DP<9>
  C3  = P5E_CPU0_P0_RX_BUF_DN<10>
  C4  = P5E_CPU0_P0_RX_BUF_DP<11>
  C5  = P5E_CPU0_P0_RX_BUF_DN<12>
  C6  = P5E_CPU0_P0_RX_BUF_DP<13>
  C7  = P5E_CPU0_P0_RX_BUF_DN<14>
  C8  = P5E_CPU0_P0_RX_BUF_DP<15>
  D1  = P5E_CPU0_P0_RX_BUF_DP<8>
  D2  = GND
  D3  = P5E_CPU0_P0_RX_BUF_DP<10>
  D4  = GND
  D5  = P5E_CPU0_P0_RX_BUF_DP<12>
  D6  = GND
  D7  = P5E_CPU0_P0_RX_BUF_DP<14>
  D8  = GND
  E1  = GND
  E2  = P5E_CPU0_P1_RX_BUF_DN<9>
  E3  = GND
  E4  = P5E_CPU0_P1_RX_BUF_DN<11>
  E5  = GND
  E6  = P5E_CPU0_P1_RX_BUF_DN<13>
  E7  = GND
  E8  = P5E_CPU0_P1_RX_BUF_DN<15>
  F1  = P5E_CPU0_P1_RX_BUF_DN<8>
  F2  = P5E_CPU0_P1_RX_BUF_DP<9>
  F3  = P5E_CPU0_P1_RX_BUF_DN<10>
  F4  = P5E_CPU0_P1_RX_BUF_DP<11>
  F5  = P5E_CPU0_P1_RX_BUF_DN<12>
  F6  = P5E_CPU0_P1_RX_BUF_DP<13>
  F7  = P5E_CPU0_P1_RX_BUF_DN<14>
  F8  = P5E_CPU0_P1_RX_BUF_DP<15>
  G1  = P5E_CPU0_P1_RX_BUF_DP<8>
  G2  = GND
  G3  = P5E_CPU0_P1_RX_BUF_DP<10>
  G4  = GND
  G5  = P5E_CPU0_P1_RX_BUF_DP<12>
  G6  = GND
  G7  = P5E_CPU0_P1_RX_BUF_DP<14>
  G8  = GND
  H1  = GND
  H2  = P5E_CPU0_P0_TX_BUF_C_DN<9>
  H3  = GND
  H4  = P5E_CPU0_P0_TX_BUF_C_DN<11>
  H5  = GND
  H6  = P5E_CPU0_P0_TX_BUF_C_DN<13>
  H7  = GND
  H8  = P5E_CPU0_P0_TX_BUF_C_DN<15>
  I1  = P5E_CPU0_P0_TX_BUF_C_DN<8>
  I2  = P5E_CPU0_P0_TX_BUF_C_DP<9>
  I3  = P5E_CPU0_P0_TX_BUF_C_DN<10>
  I4  = P5E_CPU0_P0_TX_BUF_C_DP<11>
  I5  = P5E_CPU0_P0_TX_BUF_C_DN<12>
  I6  = P5E_CPU0_P0_TX_BUF_C_DP<13>
  I7  = P5E_CPU0_P0_TX_BUF_C_DN<14>
  I8  = P5E_CPU0_P0_TX_BUF_C_DP<15>
  J1  = P5E_CPU0_P0_TX_BUF_C_DP<8>
  J2  = GND
  J3  = P5E_CPU0_P0_TX_BUF_C_DP<10>
  J4  = GND
  J5  = P5E_CPU0_P0_TX_BUF_C_DP<12>
  J6  = GND
  J7  = P5E_CPU0_P0_TX_BUF_C_DP<14>
  J8  = GND
  K1  = GND
  K2  = P5E_CPU0_P1_TX_BUF_C_DN<9>
  K3  = GND
  K4  = P5E_CPU0_P1_TX_BUF_C_DN<11>
  K5  = GND
  K6  = P5E_CPU0_P1_TX_BUF_C_DN<13>
  K7  = GND
  K8  = P5E_CPU0_P1_TX_BUF_C_DN<15>
  L1  = P5E_CPU0_P1_TX_BUF_C_DN<8>
  L2  = P5E_CPU0_P1_TX_BUF_C_DP<9>
  L3  = P5E_CPU0_P1_TX_BUF_C_DN<10>
  L4  = P5E_CPU0_P1_TX_BUF_C_DP<11>
  L5  = P5E_CPU0_P1_TX_BUF_C_DN<12>
  L6  = P5E_CPU0_P1_TX_BUF_C_DP<13>
  L7  = P5E_CPU0_P1_TX_BUF_C_DN<14>
  L8  = P5E_CPU0_P1_TX_BUF_C_DP<15>
  M1  = P5E_CPU0_P1_TX_BUF_C_DP<8>
  M2  = GND
  M3  = P5E_CPU0_P1_TX_BUF_C_DP<10>
  M4  = GND
  M5  = P5E_CPU0_P1_TX_BUF_C_DP<12>
  M6  = GND
  M7  = P5E_CPU0_P1_TX_BUF_C_DP<14>
  M8  = GND
  N1  = GND
  N2  = PRSNT_CABLE_SWB_B2_N
  N3  = GND
  N4  = NC_J107_N4
  N5  = GND
  N6  = NC_J107_N6
  N7  = GND
  N8  = SWB_HSC_EN_BUF

(kicad_pcb
	(version 20260206)
	(generator "pcbnew")
	(generator_version "10.0")
	(general
		(thickness 1.6)
		(legacy_teardrops no)
	)
	(paper "A4")
	(title_block
		(title "04192023_DAF0TMB3IC0_F0TG_MB_C_brd_V02_OCP.brd")
		(comment 1 "Grand Teton / footprint 2835 of 8354 (J107), pads 1-31 of 48")
	)
	(layers
		(0 "F.Cu" signal "TOP")
		(4 "In1.Cu" signal "GND")
		(6 "In2.Cu" signal "IN1")
		(8 "In3.Cu" signal "GND1")
		(10 "In4.Cu" signal "IN2")
		(12 "In5.Cu" signal "GND2")
		(14 "In6.Cu" signal "IN3")
		(16 "In7.Cu" signal "GND3")
		(18 "In8.Cu" signal "VCC")
		(20 "In9.Cu" signal "VCC1")
		(22 "In10.Cu" signal "GND4")
		(24 "In11.Cu" signal "IN4")
		(26 "In12.Cu" signal "GND5")
		(28 "In13.Cu" signal "IN5")
		(30 "In14.Cu" signal "GND6")
		(32 "In15.Cu" signal "IN6")
		(34 "In16.Cu" signal "GND7")
		(2 "B.Cu" signal "BOTTOM")
		(9 "F.Adhes" user "F.Adhesive")
		(11 "B.Adhes" user "B.Adhesive")
		(13 "F.Paste" user "Package Geometry/Pastemask Top")
		(15 "B.Paste" user "Package Geometry/Pastemask Bottom")
		(5 "F.SilkS" user "Ref Des/Silkscreen Top")
		(7 "B.SilkS" user "Ref Des/Silkscreen Bottom")
		(1 "F.Mask" user "Board Geometry/Soldermask Top")
		(3 "B.Mask" user "Board Geometry/Soldermask Bottom")
		(17 "Dwgs.User" user "User.Drawings")
		(19 "Cmts.User" user "User.Comments")
		(21 "Eco1.User" user "User.Eco1")
		(23 "Eco2.User" user "User.Eco2")
		(25 "Edge.Cuts" user "Board Geometry/Outline")
		(27 "Margin" user)
		(31 "F.CrtYd" user "Package Geometry/Place Bound Top")
		(29 "B.CrtYd" user "Package Geometry/Place Bound Bottom")
		(35 "F.Fab" user "Ref Des/Assembly Top")
		(33 "B.Fab" user "Ref Des/Assembly Bottom")
	)
	(footprint ""
		(layer "F.Cu")
		(at 331.649832 -440.489848)
		(property "Reference" "J107"
			(at 19.92249 18.882106 0)
			(unlocked yes)
			(layer "F.SilkS")
			(effects
				(font
					(size 0.7874 0.5842)
					(thickness 0.1524)
				)
				(justify left)
			)
		)
		(property "Value" ""
			(at 0 0 0)
			(layer "F.Fab")
			(effects
				(font
					(size 1.27 1.27)
				)
			)
		)
		(duplicate_pad_numbers_are_jumpers no)
		(pad "A1" thru_hole rect
			(at 0 0 180)
			(size 0.766318 0.766318)
			(drill 0.359918)
			(layers "*.Cu" "*.Mask")
			(remove_unused_layers no)
			(net "NC_J107_A1")
			(clearance 0.0508)
			(thermal_gap 0.0508)
			(padstack
				(mode front_inner_back)
				(layer "Inner"
					(shape circle)
					(size 0.766318 0.766318)
					(clearance 0.0508)
				)
				(layer "B.Cu"
					(shape rect)
					(size 0.766318 0.766318)
					(clearance 0.0508)
				)
			)
		)
		(pad "A2" thru_hole circle
			(at 1.999996 0.199898 180)
			(size 0.906272 0.906272)
			(drill 0.499872)
			(layers "*.Cu" "*.Mask")
			(remove_unused_layers no)
			(net "GND")
			(clearance 0.0508)
			(thermal_gap 0.0508)
		)
		(pad "A3" thru_hole circle
			(at 3.999992 0 180)
			(size 0.766318 0.766318)
			(drill 0.359918)
			(layers "*.Cu" "*.Mask")
			(remove_unused_layers no)
			(net "NC_J107_A3")
			(clearance 0.0508)
			(thermal_gap 0.0508)
		)
		(pad "A4" thru_hole circle
			(at 5.999988 0.199898 180)
			(size 0.906272 0.906272)
			(drill 0.499872)
			(layers "*.Cu" "*.Mask")
			(remove_unused_layers no)
			(net "GND")
			(clearance 0.0508)
			(thermal_gap 0.0508)
		)
		(pad "A5" thru_hole circle
			(at 7.999984 0 180)
			(size 0.766318 0.766318)
			(drill 0.359918)
			(layers "*.Cu" "*.Mask")
			(remove_unused_layers no)
			(net "NC_J107_A5")
			(clearance 0.0508)
			(thermal_gap 0.0508)
		)
		(pad "A6" thru_hole circle
			(at 9.99998 0.199898 180)
			(size 0.906272 0.906272)
			(drill 0.499872)
			(layers "*.Cu" "*.Mask")
			(remove_unused_layers no)
			(net "GND")
			(clearance 0.0508)
			(thermal_gap 0.0508)
		)
		(pad "A7" thru_hole circle
			(at 11.999976 0 180)
			(size 0.766318 0.766318)
			(drill 0.359918)
			(layers "*.Cu" "*.Mask")
			(remove_unused_layers no)
			(net "SWB_HSC_PWRGD")
			(clearance 0.0508)
			(thermal_gap 0.0508)
		)
		(pad "A8" thru_hole circle
			(at 13.999972 0.199898 180)
			(size 0.906272 0.906272)
			(drill 0.499872)
			(layers "*.Cu" "*.Mask")
			(remove_unused_layers no)
			(net "GND")
			(clearance 0.0508)
			(thermal_gap 0.0508)
		)
		(pad "B1" thru_hole circle
			(at 0 1.199896 180)
			(size 0.906272 0.906272)
			(drill 0.499872)
			(layers "*.Cu" "*.Mask")
			(remove_unused_layers no)
			(net "GND")
			(clearance 0.0508)
			(thermal_gap 0.0508)
		)
		(pad "B3" thru_hole circle
			(at 3.999992 1.199896 180)
			(size 0.906272 0.906272)
			(drill 0.499872)
			(layers "*.Cu" "*.Mask")
			(remove_unused_layers no)
			(net "GND")
			(clearance 0.0508)
			(thermal_gap 0.0508)
		)
		(pad "B5" thru_hole circle
			(at 7.999984 1.199896 180)
			(size 0.906272 0.906272)
			(drill 0.499872)
			(layers "*.Cu" "*.Mask")
			(remove_unused_layers no)
			(net "GND")
			(clearance 0.0508)
			(thermal_gap 0.0508)
		)
		(pad "B7" thru_hole circle
			(at 11.999976 1.199896 180)
			(size 0.906272 0.906272)
			(drill 0.499872)
			(layers "*.Cu" "*.Mask")
			(remove_unused_layers no)
			(net "GND")
			(clearance 0.0508)
			(thermal_gap 0.0508)
		)
		(pad "D2" thru_hole circle
			(at 1.999996 3.800094 180)
			(size 0.906272 0.906272)
			(drill 0.499872)
			(layers "*.Cu" "*.Mask")
			(remove_unused_layers no)
			(net "GND")
			(clearance 0.0508)
			(thermal_gap 0.0508)
		)
		(pad "D4" thru_hole circle
			(at 5.999988 3.800094 180)
			(size 0.906272 0.906272)
			(drill 0.499872)
			(layers "*.Cu" "*.Mask")
			(remove_unused_layers no)
			(net "GND")
			(clearance 0.0508)
			(thermal_gap 0.0508)
		)
		(pad "D6" thru_hole circle
			(at 9.99998 3.800094 180)
			(size 0.906272 0.906272)
			(drill 0.499872)
			(layers "*.Cu" "*.Mask")
			(remove_unused_layers no)
			(net "GND")
			(clearance 0.0508)
			(thermal_gap 0.0508)
		)
		(pad "D8" thru_hole circle
			(at 13.999972 3.800094 180)
			(size 0.906272 0.906272)
			(drill 0.499872)
			(layers "*.Cu" "*.Mask")
			(remove_unused_layers no)
			(net "GND")
			(clearance 0.0508)
			(thermal_gap 0.0508)
		)
		(pad "E1" thru_hole circle
			(at 0 4.800092 180)
			(size 0.906272 0.906272)
			(drill 0.499872)
			(layers "*.Cu" "*.Mask")
			(remove_unused_layers no)
			(net "GND")
			(clearance 0.0508)
			(thermal_gap 0.0508)
		)
		(pad "E3" thru_hole circle
			(at 3.999992 4.800092 180)
			(size 0.906272 0.906272)
			(drill 0.499872)
			(layers "*.Cu" "*.Mask")
			(remove_unused_layers no)
			(net "GND")
			(clearance 0.0508)
			(thermal_gap 0.0508)
		)
		(pad "E5" thru_hole circle
			(at 7.999984 4.800092 180)
			(size 0.906272 0.906272)
			(drill 0.499872)
			(layers "*.Cu" "*.Mask")
			(remove_unused_layers no)
			(net "GND")
			(clearance 0.0508)
			(thermal_gap 0.0508)
		)
		(pad "E7" thru_hole circle
			(at 11.999976 4.800092 180)
			(size 0.906272 0.906272)
			(drill 0.499872)
			(layers "*.Cu" "*.Mask")
			(remove_unused_layers no)
			(net "GND")
			(clearance 0.0508)
			(thermal_gap 0.0508)
		)
		(pad "G2" thru_hole circle
			(at 1.999996 7.400036 180)
			(size 0.906272 0.906272)
			(drill 0.499872)
			(layers "*.Cu" "*.Mask")
			(remove_unused_layers no)
			(net "GND")
			(clearance 0.0508)
			(thermal_gap 0.0508)
		)
		(pad "G4" thru_hole circle
			(at 5.999988 7.400036 180)
			(size 0.906272 0.906272)
			(drill 0.499872)
			(layers "*.Cu" "*.Mask")
			(remove_unused_layers no)
			(net "GND")
			(clearance 0.0508)
			(thermal_gap 0.0508)
		)
		(pad "G6" thru_hole circle
			(at 9.99998 7.400036 180)
			(size 0.906272 0.906272)
			(drill 0.499872)
			(layers "*.Cu" "*.Mask")
			(remove_unused_layers no)
			(net "GND")
			(clearance 0.0508)
			(thermal_gap 0.0508)
		)
		(pad "G8" thru_hole circle
			(at 13.999972 7.400036 180)
			(size 0.906272 0.906272)
			(drill 0.499872)
			(layers "*.Cu" "*.Mask")
			(remove_unused_layers no)
			(net "GND")
			(clearance 0.0508)
			(thermal_gap 0.0508)
		)
		(pad "H1" thru_hole circle
			(at 0 8.400034 180)
			(size 0.906272 0.906272)
			(drill 0.499872)
			(layers "*.Cu" "*.Mask")
			(remove_unused_layers no)
			(net "GND")
			(clearance 0.0508)
			(thermal_gap 0.0508)
		)
		(pad "H3" thru_hole circle
			(at 3.999992 8.400034 180)
			(size 0.906272 0.906272)
			(drill 0.499872)
			(layers "*.Cu" "*.Mask")
			(remove_unused_layers no)
			(net "GND")
			(clearance 0.0508)
			(thermal_gap 0.0508)
		)
		(pad "H5" thru_hole circle
			(at 7.999984 8.400034 180)
			(size 0.906272 0.906272)
			(drill 0.499872)
			(layers "*.Cu" "*.Mask")
			(remove_unused_layers no)
			(net "GND")
			(clearance 0.0508)
			(thermal_gap 0.0508)
		)
		(pad "H7" thru_hole circle
			(at 11.999976 8.400034 180)
			(size 0.906272 0.906272)
			(drill 0.499872)
			(layers "*.Cu" "*.Mask")
			(remove_unused_layers no)
			(net "GND")
			(clearance 0.0508)
			(thermal_gap 0.0508)
		)
		(pad "J2" thru_hole circle
			(at 1.999996 10.999978 180)
			(size 0.906272 0.906272)
			(drill 0.499872)
			(layers "*.Cu" "*.Mask")
			(remove_unused_layers no)
			(net "GND")
			(clearance 0.0508)
			(thermal_gap 0.0508)
		)
		(pad "J4" thru_hole circle
			(at 5.999988 10.999978 180)
			(size 0.906272 0.906272)
			(drill 0.499872)
			(layers "*.Cu" "*.Mask")
			(remove_unused_layers no)
			(net "GND")
			(clearance 0.0508)
			(thermal_gap 0.0508)
		)
		(pad "J6" thru_hole circle
			(at 9.99998 10.999978 180)
			(size 0.906272 0.906272)
			(drill 0.499872)
			(layers "*.Cu" "*.Mask")
			(remove_unused_layers no)
			(net "GND")
			(clearance 0.0508)
			(thermal_gap 0.0508)
		)
	)
)
